(kicad_pcb
	(version 20241229)
	(generator "pcbnew")
	(generator_version "9.0")
	(general
		(thickness 1.6296)
		(legacy_teardrops no)
	)
	(paper "A3")
	(title_block
		(title "Thunderbolt to 10GbE adapter")
		(date "2026-04-21")
		(rev "1.1.0")
		(company "Antmicro Ltd")
		(comment 1 "www.antmicro.com")
		(comment 9 "footprint 4 of 703 (U4), pads 80-162 of 337")
	)
	(layers
		(0 "F.Cu" signal)
		(4 "In1.Cu" signal)
		(6 "In2.Cu" signal)
		(8 "In3.Cu" signal)
		(10 "In4.Cu" signal)
		(12 "In5.Cu" signal)
		(14 "In6.Cu" signal)
		(2 "B.Cu" signal)
		(9 "F.Adhes" user "F.Adhesive")
		(11 "B.Adhes" user "B.Adhesive")
		(13 "F.Paste" user)
		(15 "B.Paste" user)
		(5 "F.SilkS" user "F.Silkscreen")
		(7 "B.SilkS" user "B.Silkscreen")
		(1 "F.Mask" user)
		(3 "B.Mask" user)
		(17 "Dwgs.User" user "User.Drawings")
		(19 "Cmts.User" user "User.Comments")
		(21 "Eco1.User" user "User.Eco1")
		(23 "Eco2.User" user "User.Eco2")
		(25 "Edge.Cuts" user)
		(27 "Margin" user)
		(31 "F.CrtYd" user "F.Courtyard")
		(29 "B.CrtYd" user "B.Courtyard")
		(35 "F.Fab" user)
		(33 "B.Fab" user)
	)
	(footprint "antmicro-footprints:JHL6340SLLSQ"
		(layer "F.Cu")
		(at 128.5 123.95 180)
		(property "Reference" "U4"
			(at 4.9 6.15 0)
			(unlocked yes)
			(layer "F.SilkS")
			(effects
				(font
					(size 0.7 0.7)
					(thickness 0.15)
				)
			)
		)
		(property "Value" "JHL6340SLLSQ"
			(at 0 6.4 180)
			(unlocked yes)
			(layer "F.Fab")
			(effects
				(font
					(size 0.7 0.7)
					(thickness 0.15)
				)
			)
		)
		(property "Datasheet" "https://www.thunderbolttechnology.net/sites/default/files/18-241_ThunderboltController_Brief_HI.pdf"
			(at 0 0 180)
			(layer "F.Fab")
			(hide yes)
			(effects
				(font
					(size 1.27 1.27)
					(thickness 0.15)
				)
			)
		)
		(property "Description" "Thunderbolt™ 3 Controller, I/O"
			(at 0 0 180)
			(layer "F.Fab")
			(hide yes)
			(effects
				(font
					(size 1.27 1.27)
					(thickness 0.15)
				)
			)
		)
		(property "Manufacturer" "Intel"
			(at 0 0 180)
			(unlocked yes)
			(layer "F.Fab")
			(hide yes)
			(effects
				(font
					(size 1 1)
					(thickness 0.15)
				)
			)
		)
		(property "MPN" "JHL6340SLLSQ"
			(at 0 0 180)
			(unlocked yes)
			(layer "F.Fab")
			(hide yes)
			(effects
				(font
					(size 1 1)
					(thickness 0.15)
				)
			)
		)
		(property "Author" "Antmicro"
			(at 0 0 180)
			(unlocked yes)
			(layer "F.Fab")
			(hide yes)
			(effects
				(font
					(size 1 1)
					(thickness 0.15)
				)
			)
		)
		(property "License" "Apache-2.0"
			(at 0 0 180)
			(unlocked yes)
			(layer "F.Fab")
			(hide yes)
			(effects
				(font
					(size 1 1)
					(thickness 0.15)
				)
			)
		)
		(sheetname "/TB Controller/")
		(sheetfile "tb.kicad_sch")
		(attr smd)
		(pad "B7" smd circle
			(at -2.3 -4.6 180)
			(size 0.254 0.254)
			(layers "F.Cu" "F.Mask" "F.Paste")
			(net 265 "unconnected-(U4E-PB_RX1_P-PadB7)")
			(pinfunction "PB_RX1_P")
			(pintype "input+no_connect")
		)
		(pad "B8" smd circle
			(at -1.84 -4.6 180)
			(size 0.254 0.254)
			(layers "F.Cu" "F.Mask" "F.Paste")
			(net 23 "GND")
			(pinfunction "VSS_ANA")
			(pintype "passive")
		)
		(pad "B9" smd circle
			(at -1.38 -4.6 180)
			(size 0.254 0.254)
			(layers "F.Cu" "F.Mask" "F.Paste")
			(net 266 "unconnected-(U4E-PB_TX1_N-PadB9)")
			(pinfunction "PB_TX1_N")
			(pintype "output+no_connect")
		)
		(pad "B10" smd circle
			(at -0.92 -4.6 180)
			(size 0.254 0.254)
			(layers "F.Cu" "F.Mask" "F.Paste")
			(net 23 "GND")
			(pinfunction "VSS_ANA")
			(pintype "passive")
		)
		(pad "B11" smd circle
			(at -0.46 -4.6 180)
			(size 0.254 0.254)
			(layers "F.Cu" "F.Mask" "F.Paste")
			(net 267 "unconnected-(U4E-PB_TX0_N-PadB11)")
			(pinfunction "PB_TX0_N")
			(pintype "output+no_connect")
		)
		(pad "B12" smd circle
			(at 0 -4.6 180)
			(size 0.254 0.254)
			(layers "F.Cu" "F.Mask" "F.Paste")
			(net 23 "GND")
			(pinfunction "VSS_ANA")
			(pintype "passive")
		)
		(pad "B13" smd circle
			(at 0.46 -4.6 180)
			(size 0.254 0.254)
			(layers "F.Cu" "F.Mask" "F.Paste")
			(net 268 "unconnected-(U4E-PB_RX0_N-PadB13)")
			(pinfunction "PB_RX0_N")
			(pintype "input+no_connect")
		)
		(pad "B14" smd circle
			(at 0.92 -4.6 180)
			(size 0.254 0.254)
			(layers "F.Cu" "F.Mask" "F.Paste")
			(net 23 "GND")
			(pinfunction "VSS_ANA")
			(pintype "passive")
		)
		(pad "B15" smd circle
			(at 1.38 -4.6 180)
			(size 0.254 0.254)
			(layers "F.Cu" "F.Mask" "F.Paste")
			(net 364 "/PD and TB DC-DC/USB3.RX1_N")
			(pinfunction "PA_RX1_N")
			(pintype "input")
		)
		(pad "B16" smd circle
			(at 1.84 -4.6 180)
			(size 0.254 0.254)
			(layers "F.Cu" "F.Mask" "F.Paste")
			(net 23 "GND")
			(pinfunction "VSS_ANA")
			(pintype "passive")
		)
		(pad "B17" smd circle
			(at 2.3 -4.6 180)
			(size 0.254 0.254)
			(layers "F.Cu" "F.Mask" "F.Paste")
			(net 174 "/TB Controller/PA_TX1_N")
			(pinfunction "PA_TX1_N")
			(pintype "output")
		)
		(pad "B18" smd circle
			(at 2.76 -4.6 180)
			(size 0.254 0.254)
			(layers "F.Cu" "F.Mask" "F.Paste")
			(net 23 "GND")
			(pinfunction "VSS_ANA")
			(pintype "passive")
		)
		(pad "B19" smd circle
			(at 3.22 -4.6 180)
			(size 0.254 0.254)
			(layers "F.Cu" "F.Mask" "F.Paste")
			(net 169 "/TB Controller/PA_TX0_N")
			(pinfunction "PA_TX0_N")
			(pintype "output")
		)
		(pad "B20" smd circle
			(at 3.68 -4.6 180)
			(size 0.254 0.254)
			(layers "F.Cu" "F.Mask" "F.Paste")
			(net 23 "GND")
			(pinfunction "VSS_ANA")
			(pintype "passive")
		)
		(pad "B21" smd circle
			(at 4.14 -4.6 180)
			(size 0.254 0.254)
			(layers "F.Cu" "F.Mask" "F.Paste")
			(net 360 "/PD and TB DC-DC/USB3.RX0_P")
			(pinfunction "PA_RX0_P")
			(pintype "input")
		)
		(pad "B22" smd circle
			(at 4.6 -4.6 180)
			(size 0.254 0.254)
			(layers "F.Cu" "F.Mask" "F.Paste")
			(net 23 "GND")
			(pinfunction "VSS_ANA")
			(pintype "passive")
		)
		(pad "B23" smd oval
			(at 5.06 -4.6 270)
			(size 0.1578 0.3302)
			(layers "F.Cu" "F.Mask" "F.Paste")
			(net 269 "unconnected-(U4F-ATEST_N-PadB23)")
			(pinfunction "ATEST_N")
			(pintype "passive+no_connect")
		)
		(pad "C1" smd oval
			(at -5.06 -4.14 270)
			(size 0.1578 0.3302)
			(layers "F.Cu" "F.Mask" "F.Paste")
			(net 426 "Net-(L2-Pad1)")
			(pinfunction "SVR_IND")
			(pintype "power_out")
		)
		(pad "C2" smd circle
			(at -4.6 -4.14 180)
			(size 0.254 0.254)
			(layers "F.Cu" "F.Mask" "F.Paste")
			(net 426 "Net-(L2-Pad1)")
			(pinfunction "SVR_IND")
			(pintype "passive")
		)
		(pad "C22" smd circle
			(at 4.6 -4.14 180)
			(size 0.254 0.254)
			(layers "F.Cu" "F.Mask" "F.Paste")
			(net 23 "GND")
			(pinfunction "MONDC_CIO_1")
			(pintype "passive")
		)
		(pad "C23" smd oval
			(at 5.06 -4.14 270)
			(size 0.1578 0.3302)
			(layers "F.Cu" "F.Mask" "F.Paste")
			(net 23 "GND")
			(pinfunction "MONDC_CIO_0")
			(pintype "passive")
		)
		(pad "D1" smd oval
			(at -5.06 -3.68 270)
			(size 0.1578 0.3302)
			(layers "F.Cu" "F.Mask" "F.Paste")
			(net 426 "Net-(L2-Pad1)")
			(pinfunction "SVR_IND")
			(pintype "passive")
		)
		(pad "D2" smd circle
			(at -4.6 -3.68 180)
			(size 0.254 0.254)
			(layers "F.Cu" "F.Mask" "F.Paste")
			(net 235 "Net-(U4C-POC_GPIO_5)")
			(pinfunction "POC_GPIO_5")
			(pintype "bidirectional")
		)
		(pad "D4" smd circle
			(at -3.9 -3.9 180)
			(size 0.254 0.254)
			(layers "F.Cu" "F.Mask" "F.Paste")
			(net 193 "Net-(U4C-POC_GPIO_2)")
			(pinfunction "POC_GPIO_2")
			(pintype "bidirectional")
		)
		(pad "D5" smd circle
			(at -3.25 -3.9 180)
			(size 0.254 0.254)
			(layers "F.Cu" "F.Mask" "F.Paste")
			(net 23 "GND")
			(pinfunction "VSS")
			(pintype "passive")
		)
		(pad "D6" smd circle
			(at -2.6 -3.9 180)
			(size 0.254 0.254)
			(layers "F.Cu" "F.Mask" "F.Paste")
			(net 23 "GND")
			(pinfunction "MONDC_SVR")
			(pintype "passive")
		)
		(pad "D8" smd circle
			(at -1.95 -3.9 180)
			(size 0.254 0.254)
			(layers "F.Cu" "F.Mask" "F.Paste")
			(net 23 "GND")
			(pinfunction "VSS_ANA")
			(pintype "passive")
		)
		(pad "D9" smd circle
			(at -1.3 -3.9 180)
			(size 0.254 0.254)
			(layers "F.Cu" "F.Mask" "F.Paste")
			(net 23 "GND")
			(pinfunction "VSS_ANA")
			(pintype "passive")
		)
		(pad "D11" smd circle
			(at -0.65 -3.9 180)
			(size 0.254 0.254)
			(layers "F.Cu" "F.Mask" "F.Paste")
			(net 23 "GND")
			(pinfunction "VSS_ANA")
			(pintype "passive")
		)
		(pad "D12" smd circle
			(at 0 -3.9 180)
			(size 0.254 0.254)
			(layers "F.Cu" "F.Mask" "F.Paste")
			(net 23 "GND")
			(pinfunction "VSS_ANA")
			(pintype "passive")
		)
		(pad "D13" smd circle
			(at 0.65 -3.9 180)
			(size 0.254 0.254)
			(layers "F.Cu" "F.Mask" "F.Paste")
			(net 23 "GND")
			(pinfunction "VSS_ANA")
			(pintype "passive")
		)
		(pad "D15" smd circle
			(at 1.3 -3.9 180)
			(size 0.254 0.254)
			(layers "F.Cu" "F.Mask" "F.Paste")
			(net 23 "GND")
			(pinfunction "VSS_ANA")
			(pintype "passive")
		)
		(pad "D16" smd circle
			(at 1.95 -3.9 180)
			(size 0.254 0.254)
			(layers "F.Cu" "F.Mask" "F.Paste")
			(net 23 "GND")
			(pinfunction "VSS_ANA")
			(pintype "passive")
		)
		(pad "D18" smd circle
			(at 2.6 -3.9 180)
			(size 0.254 0.254)
			(layers "F.Cu" "F.Mask" "F.Paste")
			(net 23 "GND")
			(pinfunction "VSS_ANA")
			(pintype "passive")
		)
		(pad "D19" smd circle
			(at 3.25 -3.9 180)
			(size 0.254 0.254)
			(layers "F.Cu" "F.Mask" "F.Paste")
			(net 270 "unconnected-(U4E-PB_USB2_D_N-PadD19)")
			(pinfunction "PB_USB2_D_N")
			(pintype "bidirectional+no_connect")
		)
		(pad "D20" smd circle
			(at 3.9 -3.9 180)
			(size 0.254 0.254)
			(layers "F.Cu" "F.Mask" "F.Paste")
			(net 395 "/PD and TB DC-DC/USB_RP.D-")
			(pinfunction "PA_USB2_D_N")
			(pintype "bidirectional")
		)
		(pad "D22" smd circle
			(at 4.6 -3.68 180)
			(size 0.254 0.254)
			(layers "F.Cu" "F.Mask" "F.Paste")
			(net 330 "/TB Controller/XTAL_25_IN")
			(pinfunction "XTAL_25_IN")
			(pintype "input")
		)
		(pad "D23" smd oval
			(at 5.06 -3.68 270)
			(size 0.1578 0.3302)
			(layers "F.Cu" "F.Mask" "F.Paste")
			(net 331 "/TB Controller/XTAL_25_OUT")
			(pinfunction "XTAL_25_OUT")
			(pintype "input")
		)
		(pad "E1" smd oval
			(at -5.06 -3.22 270)
			(size 0.1578 0.3302)
			(layers "F.Cu" "F.Mask" "F.Paste")
			(net 237 "Net-(U4D-TEST_EN)")
			(pinfunction "TEST_EN")
			(pintype "input")
		)
		(pad "E2" smd circle
			(at -4.6 -3.22 180)
			(size 0.254 0.254)
			(layers "F.Cu" "F.Mask" "F.Paste")
			(net 192 "Net-(U4C-POC_GPIO_1)")
			(pinfunction "POC_GPIO_1")
			(pintype "bidirectional")
		)
		(pad "E4" smd circle
			(at -3.9 -3.25 180)
			(size 0.254 0.254)
			(layers "F.Cu" "F.Mask" "F.Paste")
			(net 23 "GND")
			(pinfunction "VSS")
			(pintype "passive")
		)
		(pad "E5" smd circle
			(at -3.25 -3.25 180)
			(size 0.254 0.254)
			(layers "F.Cu" "F.Mask" "F.Paste")
			(net 23 "GND")
			(pinfunction "VSS")
			(pintype "passive")
		)
		(pad "E6" smd circle
			(at -2.6 -3.25 180)
			(size 0.254 0.254)
			(layers "F.Cu" "F.Mask" "F.Paste")
			(net 23 "GND")
			(pinfunction "VSS")
			(pintype "passive")
		)
		(pad "E8" smd circle
			(at -1.95 -3.25 180)
			(size 0.254 0.254)
			(layers "F.Cu" "F.Mask" "F.Paste")
			(net 23 "GND")
			(pinfunction "VSS_ANA")
			(pintype "passive")
		)
		(pad "E9" smd circle
			(at -1.3 -3.25 180)
			(size 0.254 0.254)
			(layers "F.Cu" "F.Mask" "F.Paste")
			(net 23 "GND")
			(pinfunction "VSS_ANA")
			(pintype "passive")
		)
		(pad "E11" smd circle
			(at -0.65 -3.25 180)
			(size 0.254 0.254)
			(layers "F.Cu" "F.Mask" "F.Paste")
			(net 23 "GND")
			(pinfunction "VSS_ANA")
			(pintype "passive")
		)
		(pad "E12" smd circle
			(at 0 -3.25 180)
			(size 0.254 0.254)
			(layers "F.Cu" "F.Mask" "F.Paste")
			(net 68 "/TB Controller - Power/VCC_0P9")
			(pinfunction "VCC0P9_SVR_ANA")
			(pintype "power_in")
		)
		(pad "E13" smd circle
			(at 0.65 -3.25 180)
			(size 0.254 0.254)
			(layers "F.Cu" "F.Mask" "F.Paste")
			(net 68 "/TB Controller - Power/VCC_0P9")
			(pinfunction "VCC0P9_SVR_ANA")
			(pintype "passive")
		)
		(pad "E15" smd circle
			(at 1.3 -3.25 180)
			(size 0.254 0.254)
			(layers "F.Cu" "F.Mask" "F.Paste")
			(net 23 "GND")
			(pinfunction "VSS_ANA")
			(pintype "passive")
		)
		(pad "E16" smd circle
			(at 1.95 -3.25 180)
			(size 0.254 0.254)
			(layers "F.Cu" "F.Mask" "F.Paste")
			(net 23 "GND")
			(pinfunction "VSS_ANA")
			(pintype "passive")
		)
		(pad "E18" smd circle
			(at 2.6 -3.25 180)
			(size 0.254 0.254)
			(layers "F.Cu" "F.Mask" "F.Paste")
			(net 271 "unconnected-(U4F-USB2_ATEST-PadE18)")
			(pinfunction "USB2_ATEST")
			(pintype "passive+no_connect")
		)
		(pad "E19" smd circle
			(at 3.25 -3.25 180)
			(size 0.254 0.254)
			(layers "F.Cu" "F.Mask" "F.Paste")
			(net 272 "unconnected-(U4E-PB_USB2_D_P-PadE19)")
			(pinfunction "PB_USB2_D_P")
			(pintype "bidirectional+no_connect")
		)
		(pad "E20" smd circle
			(at 3.9 -3.25 180)
			(size 0.254 0.254)
			(layers "F.Cu" "F.Mask" "F.Paste")
			(net 396 "/PD and TB DC-DC/USB_RP.D+")
			(pinfunction "PA_USB2_D_P")
			(pintype "bidirectional")
		)
		(pad "E22" smd circle
			(at 4.6 -3.22 180)
			(size 0.254 0.254)
			(layers "F.Cu" "F.Mask" "F.Paste")
			(net 23 "GND")
			(pinfunction "VSS_ANA")
			(pintype "passive")
		)
		(pad "E23" smd oval
			(at 5.06 -3.22 270)
			(size 0.1578 0.3302)
			(layers "F.Cu" "F.Mask" "F.Paste")
			(net 23 "GND")
			(pinfunction "VSS_ANA")
			(pintype "passive")
		)
		(pad "F1" smd oval
			(at -5.06 -2.76 270)
			(size 0.1578 0.3302)
			(layers "F.Cu" "F.Mask" "F.Paste")
			(net 236 "Net-(U4C-POC_GPIO_6)")
			(pinfunction "POC_GPIO_6")
			(pintype "bidirectional")
		)
		(pad "F2" smd circle
			(at -4.6 -2.76 180)
			(size 0.254 0.254)
			(layers "F.Cu" "F.Mask" "F.Paste")
			(net 371 "/TB Controller/~{PE_WAKE}")
			(pinfunction "POC_GPIO_4")
			(pintype "bidirectional")
		)
		(pad "F4" smd circle
			(at -3.9 -2.6 180)
			(size 0.254 0.254)
			(layers "F.Cu" "F.Mask" "F.Paste")
			(net 377 "/PD and TB DC-DC/RESET_N")
			(pinfunction "RESET_N")
			(pintype "input")
		)
		(pad "F5" smd circle
			(at -3.25 -2.6 180)
			(size 0.254 0.254)
			(layers "F.Cu" "F.Mask" "F.Paste")
			(net 23 "GND")
			(pinfunction "VSS")
			(pintype "passive")
		)
		(pad "F6" smd circle
			(at -2.6 -2.6 180)
			(size 0.254 0.254)
			(layers "F.Cu" "F.Mask" "F.Paste")
			(net 23 "GND")
			(pinfunction "VSS")
			(pintype "passive")
		)
		(pad "F8" smd circle
			(at -1.95 -2.6 180)
			(size 0.254 0.254)
			(layers "F.Cu" "F.Mask" "F.Paste")
			(net 57 "+3V3_TB")
			(pinfunction "VCC3P3_SX")
			(pintype "power_in")
		)
		(pad "F9" smd circle
			(at -1.3 -2.6 180)
			(size 0.254 0.254)
			(layers "F.Cu" "F.Mask" "F.Paste")
			(net 23 "GND")
			(pinfunction "VSS_ANA")
			(pintype "passive")
		)
		(pad "F11" smd circle
			(at -0.65 -2.6 180)
			(size 0.254 0.254)
			(layers "F.Cu" "F.Mask" "F.Paste")
			(net 68 "/TB Controller - Power/VCC_0P9")
			(pinfunction "VCC0P9_SVR_ANA")
			(pintype "passive")
		)
		(pad "F12" smd circle
			(at 0 -2.6 180)
			(size 0.254 0.254)
			(layers "F.Cu" "F.Mask" "F.Paste")
			(net 68 "/TB Controller - Power/VCC_0P9")
			(pinfunction "VCC0P9_SVR_ANA")
			(pintype "passive")
		)
		(pad "F13" smd circle
			(at 0.65 -2.6 180)
			(size 0.254 0.254)
			(layers "F.Cu" "F.Mask" "F.Paste")
			(net 68 "/TB Controller - Power/VCC_0P9")
			(pinfunction "VCC0P9_SVR_ANA")
			(pintype "passive")
		)
		(pad "F15" smd circle
			(at 1.3 -2.6 180)
			(size 0.254 0.254)
			(layers "F.Cu" "F.Mask" "F.Paste")
			(net 68 "/TB Controller - Power/VCC_0P9")
			(pinfunction "VCC0P9_SVR_ANA")
			(pintype "passive")
		)
		(pad "F16" smd circle
			(at 1.95 -2.6 180)
			(size 0.254 0.254)
			(layers "F.Cu" "F.Mask" "F.Paste")
			(net 23 "GND")
			(pinfunction "VSS_ANA")
			(pintype "passive")
		)
		(pad "F18" smd circle
			(at 2.6 -2.6 180)
			(size 0.254 0.254)
			(layers "F.Cu" "F.Mask" "F.Paste")
			(net 180 "Net-(U4A-VCC0P9_LVR_SENSE)")
			(pinfunction "VCC0P9_LVR")
			(pintype "power_in")
		)
		(pad "F19" smd circle
			(at 3.25 -2.6 180)
			(size 0.254 0.254)
			(layers "F.Cu" "F.Mask" "F.Paste")
			(net 234 "Net-(U4E-PB_USB2_RBIAS)")
			(pinfunction "PB_USB2_RBIAS")
			(pintype "passive")
		)
		(pad "F20" smd circle
			(at 3.9 -2.6 180)
			(size 0.254 0.254)
			(layers "F.Cu" "F.Mask" "F.Paste")
			(net 23 "GND")
			(pinfunction "VSS_ANA")
			(pintype "passive")
		)
		(pad "F22" smd circle
			(at 4.6 -2.76 180)
			(size 0.254 0.254)
			(layers "F.Cu" "F.Mask" "F.Paste")
			(net 320 "/TB Controller/TB_PCIE_TX3_N")
			(pinfunction "PCIE_TX3_N")
			(pintype "input")
		)
		(pad "F23" smd oval
			(at 5.06 -2.76 270)
			(size 0.1578 0.3302)
			(layers "F.Cu" "F.Mask" "F.Paste")
			(net 329 "/TB Controller/TB_PCIE_TX3_P")
			(pinfunction "PCIE_TX3_P")
			(pintype "input")
		)
		(pad "G1" smd oval
			(at -5.06 -2.3 270)
			(size 0.1578 0.3302)
			(layers "F.Cu" "F.Mask" "F.Paste")
			(net 184 "Net-(U4C-DPSRC_HPD)")
			(pinfunction "DPSRC_HPD")
			(pintype "passive")
		)
		(pad "G2" smd circle
			(at -4.6 -2.3 180)
			(size 0.254 0.254)
			(layers "F.Cu" "F.Mask" "F.Paste")
			(net 233 "Net-(U4E-PB_DPSRC_HPD)")
			(pinfunction "PB_DPSRC_HPD")
			(pintype "input")
		)
		(pad "G22" smd circle
			(at 4.6 -2.3 180)
			(size 0.254 0.254)
			(layers "F.Cu" "F.Mask" "F.Paste")
			(net 23 "GND")
			(pinfunction "VSS_ANA")
			(pintype "passive")
		)
		(pad "G23" smd oval
			(at 5.06 -2.3 270)
			(size 0.1578 0.3302)
			(layers "F.Cu" "F.Mask" "F.Paste")
			(net 23 "GND")
			(pinfunction "VSS_ANA")
			(pintype "passive")
		)
		(pad "H1" smd oval
			(at -5.06 -1.84 270)
			(size 0.1578 0.3302)
			(layers "F.Cu" "F.Mask" "F.Paste")
			(net 23 "GND")
			(pinfunction "VSS_ANA")
			(pintype "passive")
		)
		(pad "H2" smd circle
			(at -4.6 -1.84 180)
			(size 0.254 0.254)
			(layers "F.Cu" "F.Mask" "F.Paste")
			(net 23 "GND")
			(pinfunction "VSS_ANA")
			(pintype "passive")
		)
		(pad "H4" smd circle
			(at -3.9 -1.95 180)
			(size 0.254 0.254)
			(layers "F.Cu" "F.Mask" "F.Paste")
			(net 194 "Net-(U4C-POC_GPIO_3)")
			(pinfunction "POC_GPIO_3")
			(pintype "bidirectional")
		)
		(pad "H5" smd circle
			(at -3.25 -1.95 180)
			(size 0.254 0.254)
			(layers "F.Cu" "F.Mask" "F.Paste")
			(net 23 "GND")
			(pinfunction "VSS")
			(pintype "passive")
		)
		(pad "H6" smd circle
			(at -2.6 -1.95 180)
			(size 0.254 0.254)
			(layers "F.Cu" "F.Mask" "F.Paste")
			(net 230 "Net-(U4D-RBIAS)")
			(pinfunction "RBIAS")
			(pintype "passive")
		)
		(pad "H8" smd circle
			(at -1.95 -1.95 180)
			(size 0.254 0.254)
			(layers "F.Cu" "F.Mask" "F.Paste")
			(net 23 "GND")
			(pinfunction "VSS")
			(pintype "passive")
		)
		(pad "H9" smd circle
			(at -1.3 -1.95 180)
			(size 0.254 0.254)
			(layers "F.Cu" "F.Mask" "F.Paste")
			(net 57 "+3V3_TB")
			(pinfunction "VCC3P3A")
			(pintype "power_in")
		)
	)
)
